(kicad_pcb
	(version 20241229)
	(generator "pcbnew")
	(generator_version "9.0")
	(general
		(thickness 1.711)
		(legacy_teardrops no)
	)
	(paper "A4")
	(title_block
		(title "Antmicro Baseboard for Jetson AGX Thor")
		(date "2026-02-18")
		(rev "1.1.0")
		(company "Antmicro Ltd")
		(comment 1 "www.antmicro.com")
		(comment 9 "footprints 896-900 of 1170")
	)
	(layers
		(0 "F.Cu" signal)
		(4 "In1.Cu" signal)
		(6 "In2.Cu" signal)
		(8 "In3.Cu" signal)
		(10 "In4.Cu" jumper)
		(12 "In5.Cu" signal)
		(14 "In6.Cu" signal)
		(16 "In7.Cu" signal)
		(18 "In8.Cu" signal)
		(2 "B.Cu" signal)
		(9 "F.Adhes" user "F.Adhesive")
		(11 "B.Adhes" user "B.Adhesive")
		(13 "F.Paste" user)
		(15 "B.Paste" user)
		(5 "F.SilkS" user "F.Silkscreen")
		(7 "B.SilkS" user "B.Silkscreen")
		(1 "F.Mask" user)
		(3 "B.Mask" user)
		(17 "Dwgs.User" user "User.Drawings")
		(19 "Cmts.User" user "User.Comments")
		(21 "Eco1.User" user "User.Eco1")
		(23 "Eco2.User" user "User.Eco2")
		(25 "Edge.Cuts" user)
		(27 "Margin" user)
		(31 "F.CrtYd" user "F.Courtyard")
		(29 "B.CrtYd" user "B.Courtyard")
		(35 "F.Fab" user)
		(33 "B.Fab" user)
	)
	(footprint "antmicro-footprints:C_0402_1005Metric"
		(layer "B.Cu")
		(at 230.426 152.025)
		(descr "Capacitor SMD 0402")
		(tags "capacitor SMD 0402")
		(property "Reference" "C179"
			(at -1.56 -1.54 0)
			(layer "B.SilkS")
			(effects
				(font
					(size 0.7 0.7)
					(thickness 0.15)
				)
				(justify right top mirror)
			)
		)
		(property "Value" "C_100n_0402"
			(at -1.022927 -2.155213 0)
			(layer "B.Fab")
			(effects
				(font
					(size 0.7 0.7)
					(thickness 0.15)
				)
				(justify right top mirror)
			)
		)
		(property "Datasheet" "https://www.murata.com/products/productdetail?partno=GRM155R61H104KE14%23"
			(at 0 0 0)
			(layer "B.Fab")
			(hide yes)
			(effects
				(font
					(size 1.27 1.27)
					(thickness 0.15)
				)
				(justify mirror)
			)
		)
		(property "Description" "SMD Multilayer Ceramic Capacitor, 0.1 µF, 50 V, 0402 [1005 Metric], ± 10%, X5R, GRM Series"
			(at 0 0 0)
			(layer "B.Fab")
			(hide yes)
			(effects
				(font
					(size 1.27 1.27)
					(thickness 0.15)
				)
				(justify mirror)
			)
		)
		(property "MPN" "GRM155R61H104KE14D"
			(at 0 0 180)
			(unlocked yes)
			(layer "B.Fab")
			(hide yes)
			(effects
				(font
					(size 1 1)
					(thickness 0.15)
				)
				(justify mirror)
			)
		)
		(property "Manufacturer" "Murata"
			(at 0 0 180)
			(unlocked yes)
			(layer "B.Fab")
			(hide yes)
			(effects
				(font
					(size 1 1)
					(thickness 0.15)
				)
				(justify mirror)
			)
		)
		(property "License" "Apache-2.0"
			(at 0 0 180)
			(unlocked yes)
			(layer "B.Fab")
			(hide yes)
			(effects
				(font
					(size 1 1)
					(thickness 0.15)
				)
				(justify mirror)
			)
		)
		(property "Author" "Antmicro"
			(at 0 0 180)
			(unlocked yes)
			(layer "B.Fab")
			(hide yes)
			(effects
				(font
					(size 1 1)
					(thickness 0.15)
				)
				(justify mirror)
			)
		)
		(property "Val" "100n"
			(at 0 0 180)
			(unlocked yes)
			(layer "B.Fab")
			(hide yes)
			(effects
				(font
					(size 1 1)
					(thickness 0.15)
				)
				(justify mirror)
			)
		)
		(property "Voltage" "50V"
			(at 0 0 180)
			(unlocked yes)
			(layer "B.Fab")
			(hide yes)
			(effects
				(font
					(size 1 1)
					(thickness 0.15)
				)
				(justify mirror)
			)
		)
		(property "Dielectric" "X5R"
			(at 0 0 180)
			(unlocked yes)
			(layer "B.Fab")
			(hide yes)
			(effects
				(font
					(size 1 1)
					(thickness 0.15)
				)
				(justify mirror)
			)
		)
		(sheetname "/SFP/")
		(sheetfile "sfp.kicad_sch")
		(attr smd)
		(fp_rect
			(start -0.925 0.47)
			(end 0.925 -0.47)
			(stroke
				(width 0.05)
				(type default)
			)
			(fill no)
			(layer "B.CrtYd")
		)
		(fp_line
			(start -0.494 -0.248)
			(end -0.494 0.25)
			(stroke
				(width 0.15)
				(type solid)
			)
			(layer "B.Fab")
		)
		(fp_line
			(start -0.494 0.25)
			(end 0.504 0.25)
			(stroke
				(width 0.15)
				(type solid)
			)
			(layer "B.Fab")
		)
		(fp_line
			(start 0.504 -0.248)
			(end -0.494 -0.248)
			(stroke
				(width 0.15)
				(type solid)
			)
			(layer "B.Fab")
		)
		(fp_line
			(start 0.504 0.25)
			(end 0.504 -0.248)
			(stroke
				(width 0.15)
				(type solid)
			)
			(layer "B.Fab")
		)
		(fp_text user "Author: Antmicro"
			(at -0.939 -3.399 0)
			(layer "B.Fab")
			(effects
				(font
					(size 0.7 0.7)
					(thickness 0.15)
				)
				(justify right top mirror)
			)
		)
		(fp_text user "License: Apache-2.0"
			(at -0.939 -5.799 0)
			(layer "B.Fab")
			(effects
				(font
					(size 0.7 0.7)
					(thickness 0.15)
				)
				(justify right top mirror)
			)
		)
		(fp_text user "${REFERENCE}"
			(at -0.939 -4.599 0)
			(layer "B.Fab")
			(effects
				(font
					(size 0.7 0.7)
					(thickness 0.15)
				)
				(justify right top mirror)
			)
		)
		(pad "1" smd roundrect
			(at -0.48 0)
			(size 0.59 0.64)
			(layers "B.Cu" "B.Mask" "B.Paste")
			(roundrect_rratio 0.25)
			(net 1 "GND")
			(pintype "passive")
		)
		(pad "2" smd roundrect
			(at 0.48 0)
			(size 0.59 0.64)
			(layers "B.Cu" "B.Mask" "B.Paste")
			(roundrect_rratio 0.25)
			(net 379 "/SFP/SH")
			(pintype "passive")
		)
	)
	(footprint "antmicro-footprints:TP_SMD_0.75mm"
		(layer "B.Cu")
		(at 142.680532 74.41 90)
		(property "Reference" "TP55"
			(at 0.39 0.719468 0)
			(layer "B.SilkS")
			(effects
				(font
					(size 0.7 0.7)
					(thickness 0.15)
				)
				(justify right top mirror)
			)
		)
		(property "Value" "TP_0.75mm_SMD"
			(at 0 -1.2 90)
			(layer "B.Fab")
			(effects
				(font
					(size 0.7 0.7)
					(thickness 0.15)
				)
				(justify right top mirror)
			)
		)
		(property "Description" "SMT test point"
			(at 0 0 90)
			(layer "B.Fab")
			(hide yes)
			(effects
				(font
					(size 1.27 1.27)
					(thickness 0.15)
				)
				(justify mirror)
			)
		)
		(property "MPN" ""
			(at 0 0 270)
			(unlocked yes)
			(layer "B.Fab")
			(hide yes)
			(effects
				(font
					(size 1 1)
					(thickness 0.15)
				)
				(justify mirror)
			)
		)
		(property "Manufacturer" ""
			(at 0 0 270)
			(unlocked yes)
			(layer "B.Fab")
			(hide yes)
			(effects
				(font
					(size 1 1)
					(thickness 0.15)
				)
				(justify mirror)
			)
		)
		(property "Author" "Antmicro"
			(at 0 0 270)
			(unlocked yes)
			(layer "B.Fab")
			(hide yes)
			(effects
				(font
					(size 1 1)
					(thickness 0.15)
				)
				(justify mirror)
			)
		)
		(property "License" "Apache-2.0"
			(at 0 0 270)
			(unlocked yes)
			(layer "B.Fab")
			(hide yes)
			(effects
				(font
					(size 1 1)
					(thickness 0.15)
				)
				(justify mirror)
			)
		)
		(sheetname "/SoM_Power/")
		(sheetfile "som_power.kicad_sch")
		(attr exclude_from_pos_files exclude_from_bom)
		(fp_circle
			(center 0 0)
			(end 0.475 0)
			(stroke
				(width 0.05)
				(type default)
			)
			(fill no)
			(layer "B.CrtYd")
		)
		(fp_text user "Author: Antmicro"
			(at -0.4 -3.901 90)
			(layer "B.Fab")
			(effects
				(font
					(size 0.7 0.7)
					(thickness 0.15)
				)
				(justify right top mirror)
			)
		)
		(fp_text user "License: Apache-2.0"
			(at -0.4 -5.101 90)
			(layer "B.Fab")
			(effects
				(font
					(size 0.7 0.7)
					(thickness 0.15)
				)
				(justify right top mirror)
			)
		)
		(fp_text user "${REFERENCE}"
			(at -0.4 -2.7 90)
			(layer "B.Fab")
			(effects
				(font
					(size 0.7 0.7)
					(thickness 0.15)
				)
				(justify right top mirror)
			)
		)
		(pad "1" smd circle
			(at 0 0 90)
			(size 0.75 0.75)
			(layers "B.Cu" "B.Mask")
			(net 609 "/SoM_Power/~{MOD_SLEEP}")
			(pinfunction "1")
			(pintype "passive")
		)
	)
	(footprint "antmicro-footprints:R_0402_1005Metric"
		(layer "B.Cu")
		(at 223.5 54.75 180)
		(descr "Resistor SMD 0402")
		(tags "resistor SMD 0402")
		(property "Reference" "R177"
			(at -3 -3.15 0)
			(layer "B.SilkS")
			(effects
				(font
					(size 0.7 0.7)
					(thickness 0.15)
				)
				(justify left bottom mirror)
			)
		)
		(property "Value" "R_200R_0402"
			(at -1.011843 -1.772046 0)
			(layer "B.Fab")
			(effects
				(font
					(size 0.7 0.7)
					(thickness 0.15)
				)
				(justify left bottom mirror)
			)
		)
		(property "Datasheet" "https://www.bourns.com/docs/product-datasheets/cr.pdf"
			(at 0 0 0)
			(layer "B.Fab")
			(hide yes)
			(effects
				(font
					(size 1.27 1.27)
					(thickness 0.15)
				)
				(justify mirror)
			)
		)
		(property "Description" "SMD Chip Resistor, 200 ohm, ± 1%, 62.5 mW, 0402 [1005 Metric], Thick Film, General Purpose"
			(at 0 0 0)
			(layer "B.Fab")
			(hide yes)
			(effects
				(font
					(size 1.27 1.27)
					(thickness 0.15)
				)
				(justify mirror)
			)
		)
		(property "Manufacturer" "Bourns"
			(at 0 0 0)
			(unlocked yes)
			(layer "B.Fab")
			(hide yes)
			(effects
				(font
					(size 1 1)
					(thickness 0.15)
				)
				(justify mirror)
			)
		)
		(property "MPN" "CR0402-FX-2000GLF"
			(at 0 0 0)
			(unlocked yes)
			(layer "B.Fab")
			(hide yes)
			(effects
				(font
					(size 1 1)
					(thickness 0.15)
				)
				(justify mirror)
			)
		)
		(property "Val" "200R"
			(at 0 0 0)
			(unlocked yes)
			(layer "B.Fab")
			(hide yes)
			(effects
				(font
					(size 1 1)
					(thickness 0.15)
				)
				(justify mirror)
			)
		)
		(property "License" "Apache-2.0"
			(at 0 0 0)
			(unlocked yes)
			(layer "B.Fab")
			(hide yes)
			(effects
				(font
					(size 1 1)
					(thickness 0.15)
				)
				(justify mirror)
			)
		)
		(property "Author" "Antmicro"
			(at 0 0 0)
			(unlocked yes)
			(layer "B.Fab")
			(hide yes)
			(effects
				(font
					(size 1 1)
					(thickness 0.15)
				)
				(justify mirror)
			)
		)
		(property "Tolerance" "1%"
			(at 0 0 0)
			(unlocked yes)
			(layer "B.Fab")
			(hide yes)
			(effects
				(font
					(size 1 1)
					(thickness 0.15)
				)
				(justify mirror)
			)
		)
		(sheetname "/CSI/")
		(sheetfile "csi.kicad_sch")
		(attr smd)
		(fp_poly
			(pts
				(xy -0.925 0.47) (xy -0.925 -0.47) (xy 0.925 -0.47) (xy 0.925 0.47)
			)
			(stroke
				(width 0.05)
				(type default)
			)
			(fill no)
			(layer "B.CrtYd")
		)
		(fp_poly
			(pts
				(xy -0.5 0.25) (xy -0.5 -0.25) (xy 0.5 -0.25) (xy 0.5 0.25)
			)
			(stroke
				(width 0.15)
				(type solid)
			)
			(fill no)
			(layer "B.Fab")
		)
		(fp_text user "License: Apache-2.0"
			(at -0.949999 -5.169 0)
			(layer "B.Fab")
			(effects
				(font
					(size 0.7 0.7)
					(thickness 0.15)
				)
				(justify left bottom mirror)
			)
		)
		(fp_text user "${REFERENCE}"
			(at -0.95 -3.168 0)
			(layer "B.Fab")
			(effects
				(font
					(size 0.7 0.7)
					(thickness 0.15)
				)
				(justify left bottom mirror)
			)
		)
		(fp_text user "Author: Antmicro"
			(at -0.95 -4.169 0)
			(layer "B.Fab")
			(effects
				(font
					(size 0.7 0.7)
					(thickness 0.15)
				)
				(justify left bottom mirror)
			)
		)
		(pad "1" smd roundrect
			(at -0.48 0 180)
			(size 0.59 0.64)
			(layers "B.Cu" "B.Mask" "B.Paste")
			(roundrect_rratio 0.25)
			(net 539 "Net-(D26-A)")
			(pintype "passive")
		)
		(pad "2" smd roundrect
			(at 0.48 0 180)
			(size 0.59 0.64)
			(layers "B.Cu" "B.Mask" "B.Paste")
			(roundrect_rratio 0.25)
			(net 8 "/CSI/CSIB_3V3")
			(pintype "passive")
		)
	)
	(footprint "antmicro-footprints:TP_SMD_0.75mm"
		(layer "B.Cu")
		(at 190.4 80.6815)
		(property "Reference" "TP16"
			(at -0.4 -0.5315 90)
			(layer "B.SilkS")
			(effects
				(font
					(size 0.7 0.7)
					(thickness 0.15)
				)
				(justify right top mirror)
			)
		)
		(property "Value" "TP_0.75mm_SMD"
			(at 0 -1.2 180)
			(layer "B.Fab")
			(effects
				(font
					(size 0.7 0.7)
					(thickness 0.15)
				)
				(justify left bottom mirror)
			)
		)
		(property "Description" "SMT test point"
			(at 0 0 180)
			(layer "B.Fab")
			(hide yes)
			(effects
				(font
					(size 1.27 1.27)
					(thickness 0.15)
				)
				(justify mirror)
			)
		)
		(property "MPN" ""
			(at 0 0 180)
			(unlocked yes)
			(layer "B.Fab")
			(hide yes)
			(effects
				(font
					(size 1 1)
					(thickness 0.15)
				)
				(justify mirror)
			)
		)
		(property "Manufacturer" ""
			(at 0 0 180)
			(unlocked yes)
			(layer "B.Fab")
			(hide yes)
			(effects
				(font
					(size 1 1)
					(thickness 0.15)
				)
				(justify mirror)
			)
		)
		(property "Author" "Antmicro"
			(at 0 0 180)
			(unlocked yes)
			(layer "B.Fab")
			(hide yes)
			(effects
				(font
					(size 1 1)
					(thickness 0.15)
				)
				(justify mirror)
			)
		)
		(property "License" "Apache-2.0"
			(at 0 0 180)
			(unlocked yes)
			(layer "B.Fab")
			(hide yes)
			(effects
				(font
					(size 1 1)
					(thickness 0.15)
				)
				(justify mirror)
			)
		)
		(sheetname "/USB Debug, PD/")
		(sheetfile "usb_debug_pd.kicad_sch")
		(attr exclude_from_pos_files exclude_from_bom)
		(fp_circle
			(center 0 0)
			(end 0.475 0)
			(stroke
				(width 0.05)
				(type default)
			)
			(fill no)
			(layer "B.CrtYd")
		)
		(fp_text user "${REFERENCE}"
			(at -0.4 -2.7 180)
			(layer "B.Fab")
			(effects
				(font
					(size 0.7 0.7)
					(thickness 0.15)
				)
				(justify left bottom mirror)
			)
		)
		(fp_text user "License: Apache-2.0"
			(at -0.4 -5.101 180)
			(layer "B.Fab")
			(effects
				(font
					(size 0.7 0.7)
					(thickness 0.15)
				)
				(justify left bottom mirror)
			)
		)
		(fp_text user "Author: Antmicro"
			(at -0.4 -3.901 180)
			(layer "B.Fab")
			(effects
				(font
					(size 0.7 0.7)
					(thickness 0.15)
				)
				(justify left bottom mirror)
			)
		)
		(pad "1" smd circle
			(at 0 0)
			(size 0.75 0.75)
			(layers "B.Cu" "B.Mask")
			(net 1168 "Net-(U30A-HPD1)")
			(pinfunction "1")
			(pintype "passive")
		)
	)
	(footprint "antmicro-footprints:USON-10_2.5x1mm_P0.5mm"
		(layer "B.Cu")
		(at 139.2 60.89 90)
		(descr "USON-10 2.5x1mm_ Pitch 0.5mm")
		(tags "USON-10 2.5x1mm Pitch 0.5mm")
		(property "Reference" "U67"
			(at -1.03 -1 0)
			(layer "B.SilkS")
			(effects
				(font
					(size 0.7 0.7)
					(thickness 0.15)
				)
				(justify right top mirror)
			)
		)
		(property "Value" "TPD4E05U06QDQARQ1"
			(at 0.018 -2.499 90)
			(layer "B.Fab")
			(effects
				(font
					(size 0.7 0.7)
					(thickness 0.15)
				)
				(justify right top mirror)
			)
		)
		(property "Datasheet" "https://www.ti.com/lit/ds/symlink/tpd4e05u06-q1.pdf?HQS=dis-mous-null-mousermode-dsf-pf-null-wwe&ts=1663591265741&ref_url=https%253A%252F%252Fwww.mouser.com%252F"
			(at 0 0 90)
			(layer "B.Fab")
			(hide yes)
			(effects
				(font
					(size 1.27 1.27)
					(thickness 0.15)
				)
				(justify mirror)
			)
		)
		(property "Description" "TVS diode array, 12 kV, USON-10, 5.5 V, 0.5 pF"
			(at 0 0 90)
			(layer "B.Fab")
			(hide yes)
			(effects
				(font
					(size 1.27 1.27)
					(thickness 0.15)
				)
				(justify mirror)
			)
		)
		(property "Manufacturer" "Texas Instruments"
			(at 0 0 270)
			(unlocked yes)
			(layer "B.Fab")
			(hide yes)
			(effects
				(font
					(size 1 1)
					(thickness 0.15)
				)
				(justify mirror)
			)
		)
		(property "MPN" "TPD4E05U06QDQARQ1"
			(at 0 0 270)
			(unlocked yes)
			(layer "B.Fab")
			(hide yes)
			(effects
				(font
					(size 1 1)
					(thickness 0.15)
				)
				(justify mirror)
			)
		)
		(property "Author" "Antmicro"
			(at 0 0 270)
			(unlocked yes)
			(layer "B.Fab")
			(hide yes)
			(effects
				(font
					(size 1 1)
					(thickness 0.15)
				)
				(justify mirror)
			)
		)
		(property "License" "Apache-2.0"
			(at 0 0 270)
			(unlocked yes)
			(layer "B.Fab")
			(hide yes)
			(effects
				(font
					(size 1 1)
					(thickness 0.15)
				)
				(justify mirror)
			)
		)
		(sheetname "/Peripherals/")
		(sheetfile "peripherals.kicad_sch")
		(attr smd)
		(fp_line
			(start 0.498 -1.398)
			(end -0.5 -1.398)
			(stroke
				(width 0.15)
				(type solid)
			)
			(layer "B.SilkS")
		)
		(fp_line
			(start 0.498 1.401)
			(end -0.5 1.401)
			(stroke
				(width 0.15)
				(type solid)
			)
			(layer "B.SilkS")
		)
		(fp_circle
			(center -0.68 1.27)
			(end -0.63 1.27)
			(stroke
				(width 0.15)
				(type solid)
			)
			(fill yes)
			(layer "B.SilkS")
		)
		(fp_rect
			(start -0.8 1.5)
			(end 0.8 -1.499)
			(stroke
				(width 0.05)
				(type solid)
			)
			(fill no)
			(layer "B.CrtYd")
		)
		(fp_line
			(start -0.5 -1.249)
			(end 0.498 -1.249)
			(stroke
				(width 0.15)
				(type solid)
			)
			(layer "B.Fab")
		)
		(fp_line
			(start -0.5 1)
			(end -0.5 -1.249)
			(stroke
				(width 0.15)
				(type solid)
			)
			(layer "B.Fab")
		)
		(fp_line
			(start 0.498 1.25)
			(end 0.498 -1.249)
			(stroke
				(width 0.15)
				(type solid)
			)
			(layer "B.Fab")
		)
		(fp_line
			(start 0.498 1.25)
			(end -0.25 1.25)
			(stroke
				(width 0.15)
				(type solid)
			)
			(layer "B.Fab")
		)
		(fp_line
			(start -0.25 1.25)
			(end -0.5 1)
			(stroke
				(width 0.15)
				(type solid)
			)
			(layer "B.Fab")
		)
		(fp_text user "${REFERENCE}"
			(at -0.802 -4.498 90)
			(layer "B.Fab")
			(effects
				(font
					(size 0.7 0.7)
					(thickness 0.15)
				)
				(justify right top mirror)
			)
		)
		(fp_text user "Author: Antmicro"
			(at -0.802 -5.7 90)
			(layer "B.Fab")
			(effects
				(font
					(size 0.7 0.7)
					(thickness 0.15)
				)
				(justify right top mirror)
			)
		)
		(fp_text user "License: Apache-2.0"
			(at -0.802 -6.9 90)
			(layer "B.Fab")
			(effects
				(font
					(size 0.7 0.7)
					(thickness 0.15)
				)
				(justify right top mirror)
			)
		)
		(pad "1" smd roundrect
			(at -0.387 1 180)
			(size 0.25 0.55)
			(layers "B.Cu" "B.Mask" "B.Paste")
			(roundrect_rratio 0.25)
			(net 42 "/Peripherals/I2C_{CONN}.SCL")
			(pintype "passive")
		)
		(pad "2" smd roundrect
			(at -0.387 0.5 180)
			(size 0.25 0.55)
			(layers "B.Cu" "B.Mask" "B.Paste")
			(roundrect_rratio 0.25)
			(net 43 "/Peripherals/I2C_{CONN}.SDA")
			(pintype "passive")
		)
		(pad "3" smd roundrect
			(at -0.387 0 180)
			(size 0.4 0.55)
			(layers "B.Cu" "B.Mask" "B.Paste")
			(roundrect_rratio 0.25)
			(net 1 "GND")
			(pintype "power_in")
		)
		(pad "4" smd roundrect
			(at -0.387 -0.498 180)
			(size 0.25 0.55)
			(layers "B.Cu" "B.Mask" "B.Paste")
			(roundrect_rratio 0.25)
			(net 838 "/Peripherals/I2C_CONN1_3V3")
			(pintype "passive")
		)
		(pad "5" smd roundrect
			(at -0.387 -0.998 180)
			(size 0.25 0.55)
			(layers "B.Cu" "B.Mask" "B.Paste")
			(roundrect_rratio 0.25)
			(net 1 "GND")
			(pintype "passive")
		)
		(pad "6" smd roundrect
			(at 0.385 -0.998 180)
			(size 0.25 0.55)
			(layers "B.Cu" "B.Mask" "B.Paste")
			(roundrect_rratio 0.25)
			(net 1 "GND")
			(pintype "passive")
		)
		(pad "7" smd roundrect
			(at 0.385 -0.498 180)
			(size 0.25 0.55)
			(layers "B.Cu" "B.Mask" "B.Paste")
			(roundrect_rratio 0.25)
			(net 838 "/Peripherals/I2C_CONN1_3V3")
			(pintype "passive")
		)
		(pad "8" smd roundrect
			(at 0.385 0 180)
			(size 0.4 0.55)
			(layers "B.Cu" "B.Mask" "B.Paste")
			(roundrect_rratio 0.25)
			(net 1 "GND")
			(pintype "passive")
		)
		(pad "9" smd roundrect
			(at 0.385 0.5 180)
			(size 0.25 0.55)
			(layers "B.Cu" "B.Mask" "B.Paste")
			(roundrect_rratio 0.25)
			(net 43 "/Peripherals/I2C_{CONN}.SDA")
			(pintype "passive")
		)
		(pad "10" smd roundrect
			(at 0.385 1 180)
			(size 0.25 0.55)
			(layers "B.Cu" "B.Mask" "B.Paste")
			(roundrect_rratio 0.25)
			(net 42 "/Peripherals/I2C_{CONN}.SCL")
			(pintype "passive")
		)
	)
)
